M48
INCH,TZ
T01C.012
T02C.016
T03C.032
T04C.073
T05C.086
T06C.091
T07C.14
T08C.146
T09C.157
;EXTENTS: -33.867 -33.321 53.798  41.062  
;LEADER: 12 
;HEADER: 
;CODE  : ASCII 
;FILE  : 12432-1.rou for board 12432-1.brd
%
G90
F1
M16
T03
M16
G00X893519Y1975079
G40
M15
G01X897819
M16
G00X893519Y1801850
G40
M15
G01X897819
M16
G00X165173Y353031
G40
M15
G01X169473
M16
G00X165173Y179803
G40
M15
G01X169473
M16
G00X66748Y1639095
G40
M15
G01X71048
M16
G00X66748Y1812323
G40
M15
G01X71048
M16
G00X66748Y1233583
G40
M15
G01X71048
M16
G00X66748Y1406811
G40
M15
G01X71048
M16
G00X66748Y828070
G40
M15
G01X71048
M16
G00X66748Y1001299
G40
M15
G01X71048
M16
G00X66748Y422559
G40
M15
G01X71048
M16
G00X66748Y595787
G40
M15
G01X71048
M16
G00X66748Y17047
G40
M15
G01X71048
M16
G00X66748Y190275
G40
M15
G01X71048
M16
G00X893519Y1569567
G40
M15
G01X897819
M16
G00X893519Y1396339
G40
M15
G01X897819
M16
G00X893519Y1164055
G40
M15
G01X897819
M16
G00X893519Y990827
G40
M15
G01X897819
M16
G00X893519Y758543
G40
M15
G01X897819
M16
G00X893519Y585315
G40
M15
G01X897819
M16
G00X893519Y353031
G40
M15
G01X897819
M16
G00X893519Y179803
G40
M15
G01X897819
M16
G00X165173Y1975079
G40
M15
G01X169473
M16
G00X165173Y1801850
G40
M15
G01X169473
M16
G00X165173Y1569567
G40
M15
G01X169473
M16
G00X165173Y1396339
G40
M15
G01X169473
M16
G00X165173Y1164055
G40
M15
G01X169473
M16
G00X165173Y990827
G40
M15
G01X169473
M16
G00X165173Y758543
G40
M15
G01X169473
M16
G00X165173Y585315
G40
M15
G01X169473
M16
G40
M30
